(kicad_pcb
	(version 20260206)
	(generator "pcbnew")
	(generator_version "10.0")
	(general
		(thickness 1.6)
		(legacy_teardrops no)
	)
	(paper "A4")
	(title_block
		(title "peb — Lightning_PEB_BRD.brd")
		(comment 1 "Lightning (Wiwynn / Facebook NVMe JBOF) / footprints 827-833 of 2563")
	)
	(layers
		(0 "F.Cu" signal "TOP")
		(4 "In1.Cu" signal "L2GND")
		(6 "In2.Cu" signal "L3")
		(8 "In3.Cu" signal "L4VCC")
		(10 "In4.Cu" signal "L5VCC")
		(12 "In5.Cu" signal "L6")
		(14 "In6.Cu" signal "L7GND")
		(2 "B.Cu" signal "BOTTOM")
		(9 "F.Adhes" user "F.Adhesive")
		(11 "B.Adhes" user "B.Adhesive")
		(13 "F.Paste" user "Package Geometry/Pastemask Top")
		(15 "B.Paste" user "Package Geometry/Pastemask Bottom")
		(5 "F.SilkS" user "Ref Des/Silkscreen Top")
		(7 "B.SilkS" user "Ref Des/Silkscreen Bottom")
		(1 "F.Mask" user "Board Geometry/Soldermask Top")
		(3 "B.Mask" user "Board Geometry/Soldermask Bottom")
		(17 "Dwgs.User" user "User.Drawings")
		(19 "Cmts.User" user "User.Comments")
		(21 "Eco1.User" user "User.Eco1")
		(23 "Eco2.User" user "User.Eco2")
		(25 "Edge.Cuts" user "Board Geometry/Outline")
		(27 "Margin" user)
		(31 "F.CrtYd" user "Package Geometry/Place Bound Top")
		(29 "B.CrtYd" user "Package Geometry/Place Bound Bottom")
		(35 "F.Fab" user "Ref Des/Assembly Top")
		(33 "B.Fab" user "Ref Des/Assembly Bottom")
	)
	(footprint ""
		(layer "F.Cu")
		(at 313.563 -69.215 180)
		(property "Reference" "PTC4"
			(at 0 0 180)
			(layer "F.SilkS")
			(hide yes)
			(effects
				(font
					(size 1.27 1.27)
				)
			)
		)
		(property "Value" "SE470UF2VDM-GP"
			(at 0 -9.6012 180)
			(unlocked yes)
			(layer "F.Fab")
			(hide yes)
			(effects
				(font
					(size 1.016 1.016)
					(thickness 0.1524)
				)
			)
		)
		(property "Device Type" "CT7343H83"
			(at 0 -11.1252 180)
			(unlocked yes)
			(layer "F.Fab")
			(hide yes)
			(effects
				(font
					(size 1.016 1.016)
					(thickness 0.1524)
				)
			)
		)
		(duplicate_pad_numbers_are_jumpers no)
		(fp_line
			(start 2.286 4.8768)
			(end -2.286 4.8768)
			(stroke
				(width 0.1524)
				(type default)
			)
			(layer "F.SilkS")
		)
		(fp_line
			(start 2.286 2.032)
			(end 2.286 4.8768)
			(stroke
				(width 0.1524)
				(type default)
			)
			(layer "F.SilkS")
		)
		(fp_line
			(start 2.286 -2.032)
			(end 2.286 -4.8768)
			(stroke
				(width 0.1524)
				(type default)
			)
			(layer "F.SilkS")
		)
		(fp_line
			(start 2.286 -4.8768)
			(end -2.286 -4.8768)
			(stroke
				(width 0.1524)
				(type default)
			)
			(layer "F.SilkS")
		)
		(fp_line
			(start 2.1082 -4.699)
			(end -2.1082 -4.699)
			(stroke
				(width 0.508)
				(type default)
			)
			(layer "F.SilkS")
		)
		(fp_line
			(start -2.286 4.8768)
			(end -2.286 2.032)
			(stroke
				(width 0.1524)
				(type default)
			)
			(layer "F.SilkS")
		)
		(fp_line
			(start -2.286 -4.8768)
			(end -2.286 -2.032)
			(stroke
				(width 0.1524)
				(type default)
			)
			(layer "F.SilkS")
		)
		(fp_rect
			(start -2.1463 3.6449)
			(end 2.1463 -3.6449)
			(stroke
				(width 0)
				(type default)
			)
			(fill no)
			(layer "F.CrtYd")
		)
		(fp_poly
			(pts
				(xy -2.54 4.953) (xy -2.54 4.2926) (xy -3.81 4.2926) (xy -3.81 -4.2926) (xy -2.54 -4.2926) (xy -2.54 -4.953)
				(xy 2.54 -4.953) (xy 2.54 -4.2926) (xy 3.81 -4.2926) (xy 3.81 -1.6256) (xy 2.1463 -1.6256) (xy 2.1463 -3.6449)
				(xy -2.1463 -3.6449) (xy -2.1463 3.6449) (xy 2.1463 3.6449) (xy 2.1463 -1.6129) (xy 3.81 -1.6129)
				(xy 3.81 4.2926) (xy 2.54 4.2926) (xy 2.54 4.953)
			)
			(stroke
				(width 0)
				(type default)
			)
			(fill no)
			(layer "F.CrtYd")
		)
		(fp_rect
			(start 2.54 4.2926)
			(end 3.81 -4.2926)
			(stroke
				(width 0)
				(type default)
			)
			(fill no)
			(layer "F.Fab")
		)
		(fp_rect
			(start -2.54 4.953)
			(end 2.54 -4.953)
			(stroke
				(width 0)
				(type default)
			)
			(fill no)
			(layer "F.Fab")
		)
		(fp_rect
			(start -3.81 4.2926)
			(end -2.54 -4.2926)
			(stroke
				(width 0)
				(type default)
			)
			(fill no)
			(layer "F.Fab")
		)
		(pad "1" smd rect
			(at 0 -3.1496 180)
			(size 2.413 2.286)
			(layers "F.Cu" "F.Mask" "F.Paste")
			(net "P0V9_E")
		)
		(pad "2" smd rect
			(at 0 3.1496 180)
			(size 2.413 2.286)
			(layers "F.Cu" "F.Mask" "F.Paste")
			(net "GND")
		)
		(zone
			(layer "F.Cu")
			(hatch none 0.5)
			(connect_pads
				(clearance 0)
			)
			(min_thickness 0.25)
			(keepout
				(tracks allowed)
				(vias not_allowed)
				(pads allowed)
				(copperpour not_allowed)
				(footprints allowed)
			)
			(placement
				(enabled no)
				(sheetname "")
			)
			(fill
				(thermal_gap 0.5)
				(thermal_bridge_width 0.5)
				(island_removal_mode 0)
			)
			(polygon
				(pts
					(xy 312.0517 -67.5259) (xy 312.0517 -64.6176) (xy 315.0743 -64.6176) (xy 315.0743 -67.5132) (xy 315.0743 -67.8434)
					(xy 312.0517 -67.8434)
				)
			)
		)
		(zone
			(layer "F.Cu")
			(hatch none 0.5)
			(connect_pads
				(clearance 0)
			)
			(min_thickness 0.25)
			(keepout
				(tracks allowed)
				(vias not_allowed)
				(pads allowed)
				(copperpour not_allowed)
				(footprints allowed)
			)
			(placement
				(enabled no)
				(sheetname "")
			)
			(fill
				(thermal_gap 0.5)
				(thermal_bridge_width 0.5)
				(island_removal_mode 0)
			)
			(polygon
				(pts
					(xy 315.0743 -73.8124) (xy 312.0517 -73.8124) (xy 312.0517 -70.9168) (xy 312.0517 -70.5866) (xy 315.0743 -70.5866)
					(xy 315.0743 -70.9168)
				)
			)
		)
	)
	(footprint ""
		(layer "F.Cu")
		(at 286.4866 -33.8582 90)
		(property "Reference" "C8"
			(at 0 0 90)
			(layer "F.SilkS")
			(hide yes)
			(effects
				(font
					(size 1.27 1.27)
				)
			)
		)
		(property "Value" "SCD22U10V2KX-1GP"
			(at 1.1811 -2.7051 90)
			(unlocked yes)
			(layer "F.Fab")
			(hide yes)
			(effects
				(font
					(size 1.016 1.016)
					(thickness 0.1524)
				)
			)
		)
		(property "Device Type" "C402H22"
			(at 1.1811 -4.2291 90)
			(unlocked yes)
			(layer "F.Fab")
			(hide yes)
			(effects
				(font
					(size 1.016 1.016)
					(thickness 0.1524)
				)
			)
		)
		(duplicate_pad_numbers_are_jumpers no)
		(fp_rect
			(start -0.4318 0.9525)
			(end 0.4318 -0.9525)
			(stroke
				(width 0)
				(type default)
			)
			(fill no)
			(layer "F.CrtYd")
		)
		(fp_rect
			(start -0.4318 0.9525)
			(end 0.4318 -0.9525)
			(stroke
				(width 0)
				(type default)
			)
			(fill no)
			(layer "F.Fab")
		)
		(pad "1" smd custom
			(at 0 -0.4445 90)
			(size 0.1524 0.1524)
			(layers "F.Cu" "F.Mask" "F.Paste")
			(net "PCIE_TX_CAP_N2")
			(options
				(clearance outline)
				(anchor circle)
			)
			(primitives
				(gr_poly
					(pts
						(arc
							(start 0.3048 -0.2032)
							(mid 0.275042 -0.275042)
							(end 0.2032 -0.3048)
						)
						(arc
							(start -0.2032 -0.3048)
							(mid -0.275042 -0.275042)
							(end -0.3048 -0.2032)
						)
						(arc
							(start -0.3048 0.2032)
							(mid -0.275042 0.275042)
							(end -0.2032 0.3048)
						)
						(arc
							(start 0.2032 0.3048)
							(mid 0.275042 0.275042)
							(end 0.3048 0.2032)
						)
					)
					(width 0)
					(fill yes)
				)
			)
		)
		(pad "2" smd custom
			(at 0 0.4445 90)
			(size 0.1524 0.1524)
			(layers "F.Cu" "F.Mask" "F.Paste")
			(net "PCIE_TX_N2")
			(options
				(clearance outline)
				(anchor circle)
			)
			(primitives
				(gr_poly
					(pts
						(arc
							(start 0.3048 -0.2032)
							(mid 0.275042 -0.275042)
							(end 0.2032 -0.3048)
						)
						(arc
							(start -0.2032 -0.3048)
							(mid -0.275042 -0.275042)
							(end -0.3048 -0.2032)
						)
						(arc
							(start -0.3048 0.2032)
							(mid -0.275042 0.275042)
							(end -0.2032 0.3048)
						)
						(arc
							(start 0.2032 0.3048)
							(mid 0.275042 0.275042)
							(end 0.3048 0.2032)
						)
					)
					(width 0)
					(fill yes)
				)
			)
		)
	)
	(footprint ""
		(layer "F.Cu")
		(at 37.222176 -61.854842 90)
		(property "Reference" "TC15"
			(at 0 0 90)
			(layer "F.SilkS")
			(hide yes)
			(effects
				(font
					(size 1.27 1.27)
				)
			)
		)
		(property "Value" "SC22U25V6KX-GP-U"
			(at -2.860802 -5.279644 90)
			(unlocked yes)
			(layer "F.Fab")
			(hide yes)
			(effects
				(font
					(size 1.016 1.016)
					(thickness 0.1524)
				)
			)
		)
		(property "Device Type" "C1206-TO0D3H75"
			(at -2.860802 -6.803644 90)
			(unlocked yes)
			(layer "F.Fab")
			(hide yes)
			(effects
				(font
					(size 1.016 1.016)
					(thickness 0.1524)
				)
			)
		)
		(duplicate_pad_numbers_are_jumpers no)
		(fp_line
			(start 1.3081 -2.3749)
			(end 1.3081 2.3749)
			(stroke
				(width 0.1524)
				(type default)
			)
			(layer "F.SilkS")
		)
		(fp_line
			(start -1.3081 -2.3749)
			(end 1.3081 -2.3749)
			(stroke
				(width 0.1524)
				(type default)
			)
			(layer "F.SilkS")
		)
		(fp_line
			(start 1.3081 2.3749)
			(end -1.3081 2.3749)
			(stroke
				(width 0.1524)
				(type default)
			)
			(layer "F.SilkS")
		)
		(fp_line
			(start -1.3081 2.3749)
			(end -1.3081 -2.3749)
			(stroke
				(width 0.1524)
				(type default)
			)
			(layer "F.SilkS")
		)
		(fp_rect
			(start -0.8001 1.6002)
			(end 0.8001 -1.6002)
			(stroke
				(width 0)
				(type default)
			)
			(fill no)
			(layer "F.CrtYd")
		)
		(fp_poly
			(pts
				(xy -1.5621 2.4511) (xy -1.5621 1.6002) (xy 0.8001 1.6002) (xy 0.8001 -1.6002) (xy -0.8001 -1.6002)
				(xy -0.8001 1.5875) (xy -1.5621 1.5875) (xy -1.5621 -2.4511) (xy 1.5621 -2.4511) (xy 1.5621 2.4511)
			)
			(stroke
				(width 0)
				(type default)
			)
			(fill no)
			(layer "F.CrtYd")
		)
		(fp_rect
			(start -1.5621 2.4511)
			(end 1.5621 -2.4511)
			(stroke
				(width 0)
				(type default)
			)
			(fill no)
			(layer "F.Fab")
		)
		(pad "1" smd rect
			(at 0 -1.392936 90)
			(size 2.1082 1.4478)
			(layers "F.Cu" "F.Mask" "F.Paste")
			(net "P5V_USB_BP1_F")
		)
		(pad "2" smd rect
			(at 0 1.392936 90)
			(size 2.1082 1.4478)
			(layers "F.Cu" "F.Mask" "F.Paste")
			(net "GND")
		)
	)
	(footprint ""
		(layer "F.Cu")
		(at 212.594444 -41.069514 -90)
		(property "Reference" "C639"
			(at 0 0 270)
			(layer "F.SilkS")
			(hide yes)
			(effects
				(font
					(size 1.27 1.27)
				)
			)
		)
		(property "Value" "SCD22U10V2KX-1GP"
			(at 1.1811 -2.7051 270)
			(unlocked yes)
			(layer "F.Fab")
			(hide yes)
			(effects
				(font
					(size 1.016 1.016)
					(thickness 0.1524)
				)
			)
		)
		(property "Device Type" "C402H22"
			(at 1.1811 -4.2291 270)
			(unlocked yes)
			(layer "F.Fab")
			(hide yes)
			(effects
				(font
					(size 1.016 1.016)
					(thickness 0.1524)
				)
			)
		)
		(duplicate_pad_numbers_are_jumpers no)
		(fp_rect
			(start -0.4318 0.9525)
			(end 0.4318 -0.9525)
			(stroke
				(width 0)
				(type default)
			)
			(fill no)
			(layer "F.CrtYd")
		)
		(fp_rect
			(start -0.4318 0.9525)
			(end 0.4318 -0.9525)
			(stroke
				(width 0)
				(type default)
			)
			(fill no)
			(layer "F.Fab")
		)
		(pad "1" smd custom
			(at 0 -0.4445 270)
			(size 0.1524 0.1524)
			(layers "F.Cu" "F.Mask" "F.Paste")
			(net "PCIE_TX_CAP_N78")
			(options
				(clearance outline)
				(anchor circle)
			)
			(primitives
				(gr_poly
					(pts
						(arc
							(start 0.3048 -0.2032)
							(mid 0.275042 -0.275042)
							(end 0.2032 -0.3048)
						)
						(arc
							(start -0.2032 -0.3048)
							(mid -0.275042 -0.275042)
							(end -0.3048 -0.2032)
						)
						(arc
							(start -0.3048 0.2032)
							(mid -0.275042 0.275042)
							(end -0.2032 0.3048)
						)
						(arc
							(start 0.2032 0.3048)
							(mid 0.275042 0.275042)
							(end 0.3048 0.2032)
						)
					)
					(width 0)
					(fill yes)
				)
			)
		)
		(pad "2" smd custom
			(at 0 0.4445 270)
			(size 0.1524 0.1524)
			(layers "F.Cu" "F.Mask" "F.Paste")
			(net "PCIE_TX_N78")
			(options
				(clearance outline)
				(anchor circle)
			)
			(primitives
				(gr_poly
					(pts
						(arc
							(start 0.3048 -0.2032)
							(mid 0.275042 -0.275042)
							(end 0.2032 -0.3048)
						)
						(arc
							(start -0.2032 -0.3048)
							(mid -0.275042 -0.275042)
							(end -0.3048 -0.2032)
						)
						(arc
							(start -0.3048 0.2032)
							(mid -0.275042 0.275042)
							(end -0.2032 0.3048)
						)
						(arc
							(start 0.2032 0.3048)
							(mid 0.275042 0.275042)
							(end 0.3048 0.2032)
						)
					)
					(width 0)
					(fill yes)
				)
			)
		)
	)
	(footprint ""
		(layer "F.Cu")
		(at 294.997378 -33.694116)
		(property "Reference" "C13"
			(at 0 0 0)
			(layer "F.SilkS")
			(hide yes)
			(effects
				(font
					(size 1.27 1.27)
				)
			)
		)
		(property "Value" "SCD22U10V2KX-1GP"
			(at 1.1811 -2.7051 0)
			(unlocked yes)
			(layer "F.Fab")
			(hide yes)
			(effects
				(font
					(size 1.016 1.016)
					(thickness 0.1524)
				)
			)
		)
		(property "Device Type" "C402H22"
			(at 1.1811 -4.2291 0)
			(unlocked yes)
			(layer "F.Fab")
			(hide yes)
			(effects
				(font
					(size 1.016 1.016)
					(thickness 0.1524)
				)
			)
		)
		(duplicate_pad_numbers_are_jumpers no)
		(fp_rect
			(start -0.4318 0.9525)
			(end 0.4318 -0.9525)
			(stroke
				(width 0)
				(type default)
			)
			(fill no)
			(layer "F.CrtYd")
		)
		(fp_rect
			(start -0.4318 0.9525)
			(end 0.4318 -0.9525)
			(stroke
				(width 0)
				(type default)
			)
			(fill no)
			(layer "F.Fab")
		)
		(pad "1" smd custom
			(at 0 -0.4445)
			(size 0.1524 0.1524)
			(layers "F.Cu" "F.Mask" "F.Paste")
			(net "PCIE_TX_CAP_N4")
			(options
				(clearance outline)
				(anchor circle)
			)
			(primitives
				(gr_poly
					(pts
						(arc
							(start 0.3048 -0.2032)
							(mid 0.275042 -0.275042)
							(end 0.2032 -0.3048)
						)
						(arc
							(start -0.2032 -0.3048)
							(mid -0.275042 -0.275042)
							(end -0.3048 -0.2032)
						)
						(arc
							(start -0.3048 0.2032)
							(mid -0.275042 0.275042)
							(end -0.2032 0.3048)
						)
						(arc
							(start 0.2032 0.3048)
							(mid 0.275042 0.275042)
							(end 0.3048 0.2032)
						)
					)
					(width 0)
					(fill yes)
				)
			)
		)
		(pad "2" smd custom
			(at 0 0.4445)
			(size 0.1524 0.1524)
			(layers "F.Cu" "F.Mask" "F.Paste")
			(net "PCIE_TX_N4")
			(options
				(clearance outline)
				(anchor circle)
			)
			(primitives
				(gr_poly
					(pts
						(arc
							(start 0.3048 -0.2032)
							(mid 0.275042 -0.275042)
							(end 0.2032 -0.3048)
						)
						(arc
							(start -0.2032 -0.3048)
							(mid -0.275042 -0.275042)
							(end -0.3048 -0.2032)
						)
						(arc
							(start -0.3048 0.2032)
							(mid -0.275042 0.275042)
							(end -0.2032 0.3048)
						)
						(arc
							(start 0.2032 0.3048)
							(mid 0.275042 0.275042)
							(end 0.3048 0.2032)
						)
					)
					(width 0)
					(fill yes)
				)
			)
		)
	)
	(footprint ""
		(layer "F.Cu")
		(at 51.181 -147.447 -90)
		(property "Reference" "C326"
			(at 0 0 270)
			(layer "F.SilkS")
			(hide yes)
			(effects
				(font
					(size 1.27 1.27)
				)
			)
		)
		(property "Value" "SCD1U16V2KX-3GP"
			(at 1.1811 -2.7051 270)
			(unlocked yes)
			(layer "F.Fab")
			(hide yes)
			(effects
				(font
					(size 1.016 1.016)
					(thickness 0.1524)
				)
			)
		)
		(property "Device Type" "C402H22"
			(at 1.1811 -4.2291 270)
			(unlocked yes)
			(layer "F.Fab")
			(hide yes)
			(effects
				(font
					(size 1.016 1.016)
					(thickness 0.1524)
				)
			)
		)
		(duplicate_pad_numbers_are_jumpers no)
		(fp_rect
			(start -0.4318 0.9525)
			(end 0.4318 -0.9525)
			(stroke
				(width 0)
				(type default)
			)
			(fill no)
			(layer "F.CrtYd")
		)
		(fp_rect
			(start -0.4318 0.9525)
			(end 0.4318 -0.9525)
			(stroke
				(width 0)
				(type default)
			)
			(fill no)
			(layer "F.Fab")
		)
		(pad "1" smd custom
			(at 0 -0.4445 270)
			(size 0.1524 0.1524)
			(layers "F.Cu" "F.Mask" "F.Paste")
			(net "P3V3_STBY")
			(options
				(clearance outline)
				(anchor circle)
			)
			(primitives
				(gr_poly
					(pts
						(arc
							(start 0.3048 -0.2032)
							(mid 0.275042 -0.275042)
							(end 0.2032 -0.3048)
						)
						(arc
							(start -0.2032 -0.3048)
							(mid -0.275042 -0.275042)
							(end -0.3048 -0.2032)
						)
						(arc
							(start -0.3048 0.2032)
							(mid -0.275042 0.275042)
							(end -0.2032 0.3048)
						)
						(arc
							(start 0.2032 0.3048)
							(mid 0.275042 0.275042)
							(end 0.3048 0.2032)
						)
					)
					(width 0)
					(fill yes)
				)
			)
		)
		(pad "2" smd custom
			(at 0 0.4445 270)
			(size 0.1524 0.1524)
			(layers "F.Cu" "F.Mask" "F.Paste")
			(net "GND")
			(options
				(clearance outline)
				(anchor circle)
			)
			(primitives
				(gr_poly
					(pts
						(arc
							(start 0.3048 -0.2032)
							(mid 0.275042 -0.275042)
							(end 0.2032 -0.3048)
						)
						(arc
							(start -0.2032 -0.3048)
							(mid -0.275042 -0.275042)
							(end -0.3048 -0.2032)
						)
						(arc
							(start -0.3048 0.2032)
							(mid -0.275042 0.275042)
							(end -0.2032 0.3048)
						)
						(arc
							(start 0.2032 0.3048)
							(mid 0.275042 0.275042)
							(end 0.3048 0.2032)
						)
					)
					(width 0)
					(fill yes)
				)
			)
		)
	)
	(footprint ""
		(layer "F.Cu")
		(at 129.159 -208.8896 180)
		(property "Reference" "R7955"
			(at 0 0 180)
			(layer "F.SilkS")
			(hide yes)
			(effects
				(font
					(size 1.27 1.27)
				)
			)
		)
		(property "Value" "0R2J-2-GP"
			(at 0.064008 -3.993896 180)
			(unlocked yes)
			(layer "F.Fab")
			(hide yes)
			(effects
				(font
					(size 1.016 1.016)
					(thickness 0.1524)
				)
			)
		)
		(property "Device Type" "R402H16"
			(at 0.064008 -5.517896 180)
			(unlocked yes)
			(layer "F.Fab")
			(hide yes)
			(effects
				(font
					(size 1.016 1.016)
					(thickness 0.1524)
				)
			)
		)
		(duplicate_pad_numbers_are_jumpers no)
		(fp_line
			(start 0.508 -0.9398)
			(end -0.508 -0.9398)
			(stroke
				(width 0.1524)
				(type default)
			)
			(layer "F.SilkS")
		)
		(fp_line
			(start -0.508 -0.9398)
			(end -0.508 0.9398)
			(stroke
				(width 0.1524)
				(type default)
			)
			(layer "F.SilkS")
		)
		(fp_rect
			(start -0.508 0.9398)
			(end 0.508 -0.9398)
			(stroke
				(width 0)
				(type default)
			)
			(fill no)
			(layer "F.CrtYd")
		)
		(fp_rect
			(start -0.508 0.9398)
			(end 0.508 -0.9398)
			(stroke
				(width 0)
				(type default)
			)
			(fill no)
			(layer "F.Fab")
		)
		(pad "1" smd custom
			(at 0 -0.4445 180)
			(size 0.1397 0.1397)
			(layers "F.Cu" "F.Mask" "F.Paste")
			(net "SSD_PWREN7")
			(options
				(clearance outline)
				(anchor circle)
			)
			(primitives
				(gr_poly
					(pts
						(arc
							(start -0.1778 -0.2794)
							(mid -0.249642 -0.249642)
							(end -0.2794 -0.1778)
						)
						(arc
							(start -0.2794 0.1778)
							(mid -0.249642 0.249642)
							(end -0.1778 0.2794)
						)
						(arc
							(start 0.1778 0.2794)
							(mid 0.249642 0.249642)
							(end 0.2794 0.1778)
						)
						(arc
							(start 0.2794 -0.1778)
							(mid 0.249642 -0.249642)
							(end 0.1778 -0.2794)
						)
					)
					(width 0)
					(fill yes)
				)
			)
		)
		(pad "2" smd custom
			(at 0 0.4445 180)
			(size 0.1397 0.1397)
			(layers "F.Cu" "F.Mask" "F.Paste")
			(net "SSD_PWREN7_R")
			(options
				(clearance outline)
				(anchor circle)
			)
			(primitives
				(gr_poly
					(pts
						(arc
							(start -0.1778 -0.2794)
							(mid -0.249642 -0.249642)
							(end -0.2794 -0.1778)
						)
						(arc
							(start -0.2794 0.1778)
							(mid -0.249642 0.249642)
							(end -0.1778 0.2794)
						)
						(arc
							(start 0.1778 0.2794)
							(mid 0.249642 0.249642)
							(end 0.2794 0.1778)
						)
						(arc
							(start 0.2794 -0.1778)
							(mid 0.249642 -0.249642)
							(end 0.1778 -0.2794)
						)
					)
					(width 0)
					(fill yes)
				)
			)
		)
	)
)
